FILE_TYPE = MACRO_DRAWING;
SET COLOR_WIRE YELLOW;
SET COLOR_PROP ORANGE;
SET COLOR_DOT WHITE;
SET COLOR_ARC YELLOW;
SET COLOR_BODY GREEN;
SET COLOR_NOTE PURPLE;
SET PROP_DISPLAY VALUE;
SET PAGE_NUMBER P259;
FORCEADD QUANTA_TITLE_BLOCK_C..1
(75 -2850);
FORCEPROP 1 LAST CUSTOM_TXT_CDS <NAME_2>
J 0
(-3100 -2800);
FORCEPROP 1 LAST CUSTOM_TXT_CDS <NAME_1>
J 0
(-3100 -2675);
FORCEPROP 1 LAST CUSTOM_TXT_CDS <Q_NUMBER>
J 0
(-1328 -2747);
DISPLAY 1.212766 (-1328 -2747);
FORCEPROP 1 LAST CUSTOM_TXT_CDS <Q_PROJ>
J 0
(-2307 -2748);
DISPLAY 1.212766 (-2307 -2748);
FORCEPROP 1 LAST CUSTOM_TXT_CDS <Q_REV>
J 0
(-109 -2747);
DISPLAY 1.212766 (-109 -2747);
FORCEPROP 1 LAST CUSTOM_TXT_CDS <CON_LAST_MODIFIED>
J 0
(-1810 -2835);
DISPLAY 0.978723 (-1810 -2835);
FORCEPROP 1 LAST CUSTOM_TXT_CDS <CON_PAGE_NUM> OF <CON_TOTAL_PAGES>
J 0
(-371 -2832);
DISPLAY 0.978723 (-371 -2832);
FORCEPROP 1 LAST Q_TITLE BLANK
J 0
(-9291 -2824);
DISPLAY 2.446809 (-9291 -2824);
PAINT GREEN (-9291 -2824);
FORCEPROP 1 LAST Q_DEPT 
J 1
(-3688 -2801);
DISPLAY 1.957447 (-3688 -2801);
PAINT GREEN (-3688 -2801);
FORCEPROP 2 LAST CDS_XR_PAGE_TITLE CR-273 : @S9S_MB_2U_LIB.S9S_MB_2U(SCH_1):PAGE273
J 0
(-7815 2400);
DISPLAY 0.638298 (-7815 2400);
PAINT PINK (-7815 2400);
DISPLAY INVISIBLE (-7815 2400);
FORCEPROP 1 LAST COMMENT_BODY TRUE
J 0
(87 -2863);
DISPLAY 0.978723 (87 -2863);
PAINT GREEN (87 -2863);
DISPLAY INVISIBLE (87 -2863);
FORCEPROP 1 LAST CDS_LMAN_SYM_OUTLINE -9475,6775,100,-125
J 0
(75 -2850);
DISPLAY 0.468085 (75 -2850);
PAINT GREEN (75 -2850);
DISPLAY INVISIBLE (75 -2850);
FORCEPROP 2 LAST CDS_LIB pure_quanta
J 0
(75 -2850);
DISPLAY INVISIBLE (75 -2850);
FORCEPROP 2 LAST PAGE_BORDER TRUE
J 0
(-7815 2400);
DISPLAY 0.638298 (-7815 2400);
PAINT PINK (-7815 2400);
DISPLAY INVISIBLE (-7815 2400);
FORCEPROP 2 LAST CUSTOM_TXT_CDS <XR_PAGE_TITLE>
J 0
(-7815 2400);
DISPLAY 0.638298 (-7815 2400);
PAINT PINK (-7815 2400);
DISPLAY INVISIBLE (-7815 2400);
FORCEPROP 0 LAST CDS_CON_LAST_MODIFIED Thu Aug 24 16:16:33 2023
J 0
(-1810 -2835);
DISPLAY INVISIBLE (-1810 -2835);
QUIT
